# BASEBOARD_FAB2 (Tioga Pass) — schematic netlist excerpt (pin names and nets, part order shuffled) for the footprints in the layout excerpt that follows; sources: Cadence DE-HDL packaged netlist, KiCad conversion of Wiwynn_Tioga_Pass_MB.brd

R6N13  RES  1.00K 1% CHIP  pkg 0402  page 156 : A = GND ; B = PD_PIROM_CPU0_ADDR1
C2U3  CAP  0.22UF 16V 10% X7R  pkg 0402  page 107 : A = P3E_CPU0_PE1_PCH_RXP<0> ; B = P3E_CPU0_PE1_SS_RXP<0>
FB2T1  HCB1608KF-800T30-GP  pkg DISCRET-G9  page 149 : \1\ = P3V3_STBY ; \2\ = VCC_VA_3V3

(kicad_pcb
	(version 20260206)
	(generator "pcbnew")
	(generator_version "10.0")
	(general
		(thickness 1.6)
		(legacy_teardrops no)
	)
	(paper "A4")
	(title_block
		(title "Wiwynn_Tioga_Pass_MB.brd")
		(comment 1 "Tioga Pass / footprints 3216-3218 of 4770")
	)
	(layers
		(0 "F.Cu" signal "TOP")
		(4 "In1.Cu" signal "L2GND")
		(6 "In2.Cu" signal "L3")
		(8 "In3.Cu" signal "L4GND")
		(10 "In4.Cu" signal "L5")
		(12 "In5.Cu" signal "L6GND")
		(14 "In6.Cu" signal "L7VCC")
		(16 "In7.Cu" signal "L8VCC")
		(18 "In8.Cu" signal "L9GND")
		(20 "In9.Cu" signal "L10")
		(22 "In10.Cu" signal "L11GND")
		(24 "In11.Cu" signal "L12")
		(26 "In12.Cu" signal "L13GND")
		(2 "B.Cu" signal "BOTTOM")
		(9 "F.Adhes" user "F.Adhesive")
		(11 "B.Adhes" user "B.Adhesive")
		(13 "F.Paste" user "Package Geometry/Pastemask Top")
		(15 "B.Paste" user "Package Geometry/Pastemask Bottom")
		(5 "F.SilkS" user "Ref Des/Silkscreen Top")
		(7 "B.SilkS" user "Ref Des/Silkscreen Bottom")
		(1 "F.Mask" user "Board Geometry/Soldermask Top")
		(3 "B.Mask" user "Board Geometry/Soldermask Bottom")
		(17 "Dwgs.User" user "User.Drawings")
		(19 "Cmts.User" user "User.Comments")
		(21 "Eco1.User" user "User.Eco1")
		(23 "Eco2.User" user "User.Eco2")
		(25 "Edge.Cuts" user "Board Geometry/Outline")
		(27 "Margin" user)
		(31 "F.CrtYd" user "Package Geometry/Place Bound Top")
		(29 "B.CrtYd" user "Package Geometry/Place Bound Bottom")
		(35 "F.Fab" user "Ref Des/Assembly Top")
		(33 "B.Fab" user "Ref Des/Assembly Bottom")
	)
	(footprint ""
		(layer "B.Cu")
		(at 194.6402 -102.6668 180)
		(property "Reference" "R6N13"
			(at 0 0 0)
			(layer "B.SilkS")
			(hide yes)
			(effects
				(font
					(size 1.27 1.27)
				)
				(justify mirror)
			)
		)
		(property "Value" ""
			(at 0 0 0)
			(layer "B.Fab")
			(effects
				(font
					(size 1.27 1.27)
				)
				(justify mirror)
			)
		)
		(duplicate_pad_numbers_are_jumpers no)
		(fp_poly
			(pts
				(xy 0.2794 -0.1016) (xy -0.2794 -0.1016) (xy -0.2794 0.9906) (xy 0.2794 0.9906)
			)
			(stroke
				(width 0)
				(type default)
			)
			(fill no)
			(layer "B.CrtYd")
		)
		(fp_line
			(start 0.2794 0.9906)
			(end -0.2794 0.9906)
			(stroke
				(width 0.1)
				(type default)
			)
			(layer "B.Fab")
		)
		(fp_line
			(start 0.2794 -0.1016)
			(end 0.2794 0.9906)
			(stroke
				(width 0.1)
				(type default)
			)
			(layer "B.Fab")
		)
		(fp_line
			(start -0.2794 0.9906)
			(end -0.2794 -0.1016)
			(stroke
				(width 0.1)
				(type default)
			)
			(layer "B.Fab")
		)
		(fp_line
			(start -0.2794 -0.1016)
			(end 0.2794 -0.1016)
			(stroke
				(width 0.1)
				(type default)
			)
			(layer "B.Fab")
		)
		(pad "1" smd rect
			(at 0 0)
			(size 0.508 0.508)
			(layers "B.Cu" "B.Mask" "B.Paste")
			(net "GND")
		)
		(pad "2" smd rect
			(at 0 0.889)
			(size 0.508 0.508)
			(layers "B.Cu" "B.Mask" "B.Paste")
			(net "PD_PIROM_CPU0_ADDR1")
		)
		(zone
			(layer "B.Cu")
			(hatch none 0.5)
			(connect_pads
				(clearance 0)
			)
			(min_thickness 0.25)
			(keepout
				(tracks not_allowed)
				(vias allowed)
				(pads allowed)
				(copperpour not_allowed)
				(footprints allowed)
			)
			(placement
				(enabled no)
				(sheetname "")
			)
			(fill
				(thermal_gap 0.5)
				(thermal_bridge_width 0.5)
				(island_removal_mode 0)
			)
			(polygon
				(pts
					(xy 194.3862 -103.3018) (xy 194.8942 -103.3018) (xy 194.8942 -102.9208) (xy 194.3862 -102.9208)
				)
			)
		)
		(zone
			(layer "B.Cu")
			(hatch none 0.5)
			(connect_pads
				(clearance 0)
			)
			(min_thickness 0.25)
			(keepout
				(tracks allowed)
				(vias not_allowed)
				(pads allowed)
				(copperpour not_allowed)
				(footprints allowed)
			)
			(placement
				(enabled no)
				(sheetname "")
			)
			(fill
				(thermal_gap 0.5)
				(thermal_bridge_width 0.5)
				(island_removal_mode 0)
			)
			(polygon
				(pts
					(xy 194.3862 -102.9208) (xy 194.8942 -102.9208) (xy 194.8942 -103.3018) (xy 194.3862 -103.3018)
				)
			)
		)
	)
	(footprint ""
		(layer "B.Cu")
		(at 333.346806 -61.257434)
		(property "Reference" "C2U3"
			(at 0 0 0)
			(layer "B.SilkS")
			(hide yes)
			(effects
				(font
					(size 1.27 1.27)
				)
				(justify mirror)
			)
		)
		(property "Value" ""
			(at 0 0 0)
			(layer "B.Fab")
			(effects
				(font
					(size 1.27 1.27)
				)
				(justify mirror)
			)
		)
		(duplicate_pad_numbers_are_jumpers no)
		(fp_poly
			(pts
				(xy -0.3048 -0.1016) (xy -0.3048 0.9906) (xy 0.3048 0.9906) (xy 0.3048 -0.1016)
			)
			(stroke
				(width 0)
				(type default)
			)
			(fill no)
			(layer "B.CrtYd")
		)
		(fp_line
			(start -0.3048 -0.1016)
			(end 0.3048 -0.1016)
			(stroke
				(width 0.1)
				(type default)
			)
			(layer "B.Fab")
		)
		(fp_line
			(start -0.3048 0.9906)
			(end -0.3048 -0.1016)
			(stroke
				(width 0.1)
				(type default)
			)
			(layer "B.Fab")
		)
		(fp_line
			(start 0.3048 -0.1016)
			(end 0.3048 0.9906)
			(stroke
				(width 0.1)
				(type default)
			)
			(layer "B.Fab")
		)
		(fp_line
			(start 0.3048 0.9906)
			(end -0.3048 0.9906)
			(stroke
				(width 0.1)
				(type default)
			)
			(layer "B.Fab")
		)
		(pad "1" smd rect
			(at 0 0 180)
			(size 0.508 0.508)
			(layers "B.Cu" "B.Mask" "B.Paste")
			(net "P3E_CPU0_PE1_PCH_RXP<0>")
		)
		(pad "2" smd rect
			(at 0 0.889 180)
			(size 0.508 0.508)
			(layers "B.Cu" "B.Mask" "B.Paste")
			(net "P3E_CPU0_PE1_SS_RXP<0>")
		)
		(zone
			(layer "B.Cu")
			(hatch none 0.5)
			(connect_pads
				(clearance 0)
			)
			(min_thickness 0.25)
			(keepout
				(tracks allowed)
				(vias not_allowed)
				(pads allowed)
				(copperpour not_allowed)
				(footprints allowed)
			)
			(placement
				(enabled no)
				(sheetname "")
			)
			(fill
				(thermal_gap 0.5)
				(thermal_bridge_width 0.5)
				(island_removal_mode 0)
			)
			(polygon
				(pts
					(xy 333.600806 -61.003434) (xy 333.092806 -61.003434) (xy 333.092806 -60.622434) (xy 333.600806 -60.622434)
				)
			)
		)
		(zone
			(layer "B.Cu")
			(hatch none 0.5)
			(connect_pads
				(clearance 0)
			)
			(min_thickness 0.25)
			(keepout
				(tracks not_allowed)
				(vias allowed)
				(pads allowed)
				(copperpour not_allowed)
				(footprints allowed)
			)
			(placement
				(enabled no)
				(sheetname "")
			)
			(fill
				(thermal_gap 0.5)
				(thermal_bridge_width 0.5)
				(island_removal_mode 0)
			)
			(polygon
				(pts
					(xy 333.600806 -60.622434) (xy 333.092806 -60.622434) (xy 333.092806 -61.003434) (xy 333.600806 -61.003434)
				)
			)
		)
	)
	(footprint ""
		(layer "B.Cu")
		(at 410.679646 -25.790652 180)
		(property "Reference" "FB2T1"
			(at 0 0 0)
			(layer "B.SilkS")
			(hide yes)
			(effects
				(font
					(size 1.27 1.27)
				)
				(justify mirror)
			)
		)
		(property "Value" "*"
			(at -0.0254 -2.8829 180)
			(unlocked yes)
			(layer "B.Fab")
			(hide yes)
			(effects
				(font
					(size 1.27 1.016)
					(thickness 0.1524)
				)
				(justify mirror)
			)
		)
		(property "Device Type" "HCB1608KF-800T30-GP_DISCRET-G9A"
			(at -0.0254 -4.4069 180)
			(unlocked yes)
			(layer "B.Fab")
			(hide yes)
			(effects
				(font
					(size 1.27 1.016)
					(thickness 0.1524)
				)
				(justify mirror)
			)
		)
		(duplicate_pad_numbers_are_jumpers no)
		(fp_line
			(start -0.254 0)
			(end 0.254 0)
			(stroke
				(width 0.2032)
				(type default)
			)
			(layer "B.SilkS")
		)
		(fp_rect
			(start 0.5842 1.3335)
			(end -0.5842 -1.3335)
			(stroke
				(width 0)
				(type default)
			)
			(fill no)
			(layer "B.CrtYd")
		)
		(fp_rect
			(start 0.5842 1.3335)
			(end -0.5842 -1.3335)
			(stroke
				(width 0)
				(type default)
			)
			(fill no)
			(layer "B.Fab")
		)
		(pad "1" smd custom
			(at 0 -0.762)
			(size 0.2159 0.2159)
			(layers "B.Cu" "B.Mask" "B.Paste")
			(net "P3V3_STBY")
			(options
				(clearance outline)
				(anchor circle)
			)
			(primitives
				(gr_poly
					(pts
						(arc
							(start -0.3302 0.4318)
							(mid -0.402042 0.402042)
							(end -0.4318 0.3302)
						)
						(arc
							(start -0.4318 -0.3302)
							(mid -0.402042 -0.402042)
							(end -0.3302 -0.4318)
						)
						(arc
							(start 0.3302 -0.4318)
							(mid 0.402042 -0.402042)
							(end 0.4318 -0.3302)
						)
						(arc
							(start 0.4318 0.3302)
							(mid 0.402042 0.402042)
							(end 0.3302 0.4318)
						)
					)
					(width 0)
					(fill yes)
				)
			)
		)
		(pad "2" smd custom
			(at 0 0.762)
			(size 0.2159 0.2159)
			(layers "B.Cu" "B.Mask" "B.Paste")
			(net "VCC_VA_3V3")
			(options
				(clearance outline)
				(anchor circle)
			)
			(primitives
				(gr_poly
					(pts
						(arc
							(start -0.3302 0.4318)
							(mid -0.402042 0.402042)
							(end -0.4318 0.3302)
						)
						(arc
							(start -0.4318 -0.3302)
							(mid -0.402042 -0.402042)
							(end -0.3302 -0.4318)
						)
						(arc
							(start 0.3302 -0.4318)
							(mid 0.402042 -0.402042)
							(end 0.4318 -0.3302)
						)
						(arc
							(start 0.4318 0.3302)
							(mid 0.402042 0.402042)
							(end 0.3302 0.4318)
						)
					)
					(width 0)
					(fill yes)
				)
			)
		)
	)
)
